# S9S_MB_2U (Grand Teton) — schematic netlist excerpt (pin names and nets, part order shuffled) for the footprints in the layout excerpt that follows; sources: Cadence DE-HDL packaged netlist, KiCad conversion of 03242023_DA0F0TMBIJ0_F0T_Motherboard_J_brd_V01_OCP.brd

R1500  Q_RES  4.75K 1% CHIP  pkg 0402LF  page 208 : A = PD_CK440_SBI_DATA_IN ; B = GND
R2522  Q_RES  1K 1% CHIP  pkg 0402LF  page 284 : A = P3V3_AUX ; B = IRQ_PVCCIN_CPU1_VRHOT_R_N

(kicad_pcb
	(version 20260206)
	(generator "pcbnew")
	(generator_version "10.0")
	(general
		(thickness 1.6)
		(legacy_teardrops no)
	)
	(paper "A4")
	(title_block
		(title "03242023_DA0F0TMBIJ0_F0T_Motherboard_J_brd_V01_OCP.brd")
		(comment 1 "Grand Teton / footprints 5361-5362 of 6105")
	)
	(layers
		(0 "F.Cu" signal "TOP")
		(4 "In1.Cu" signal "GND")
		(6 "In2.Cu" signal "IN1")
		(8 "In3.Cu" signal "GND1")
		(10 "In4.Cu" signal "IN2")
		(12 "In5.Cu" signal "GND2")
		(14 "In6.Cu" signal "IN3")
		(16 "In7.Cu" signal "GND3")
		(18 "In8.Cu" signal "VCC")
		(20 "In9.Cu" signal "VCC1")
		(22 "In10.Cu" signal "GND4")
		(24 "In11.Cu" signal "IN4")
		(26 "In12.Cu" signal "GND5")
		(28 "In13.Cu" signal "IN5")
		(30 "In14.Cu" signal "GND6")
		(32 "In15.Cu" signal "IN6")
		(34 "In16.Cu" signal "GND7")
		(2 "B.Cu" signal "BOTTOM")
		(9 "F.Adhes" user "F.Adhesive")
		(11 "B.Adhes" user "B.Adhesive")
		(13 "F.Paste" user "Package Geometry/Pastemask Top")
		(15 "B.Paste" user "Package Geometry/Pastemask Bottom")
		(5 "F.SilkS" user "Ref Des/Silkscreen Top")
		(7 "B.SilkS" user "Ref Des/Silkscreen Bottom")
		(1 "F.Mask" user "Board Geometry/Soldermask Top")
		(3 "B.Mask" user "Board Geometry/Soldermask Bottom")
		(17 "Dwgs.User" user "User.Drawings")
		(19 "Cmts.User" user "User.Comments")
		(21 "Eco1.User" user "User.Eco1")
		(23 "Eco2.User" user "User.Eco2")
		(25 "Edge.Cuts" user "Board Geometry/Outline")
		(27 "Margin" user)
		(31 "F.CrtYd" user "Package Geometry/Place Bound Top")
		(29 "B.CrtYd" user "Package Geometry/Place Bound Bottom")
		(35 "F.Fab" user "Ref Des/Assembly Top")
		(33 "B.Fab" user "Ref Des/Assembly Bottom")
	)
	(footprint ""
		(layer "B.Cu")
		(at 252.718824 -108.179108 -90)
		(property "Reference" "R1500"
			(at 0 0 90)
			(layer "B.SilkS")
			(hide yes)
			(effects
				(font
					(size 1.27 1.27)
				)
				(justify mirror)
			)
		)
		(property "Value" ""
			(at 0 0 90)
			(layer "B.Fab")
			(effects
				(font
					(size 1.27 1.27)
				)
				(justify mirror)
			)
		)
		(duplicate_pad_numbers_are_jumpers no)
		(fp_line
			(start -0.7874 0.4064)
			(end 0.7874 0.4064)
			(stroke
				(width 0.1524)
				(type default)
			)
			(layer "B.SilkS")
		)
		(fp_line
			(start 0.7874 0.4064)
			(end 0.7874 -0.4064)
			(stroke
				(width 0.1524)
				(type default)
			)
			(layer "B.SilkS")
		)
		(fp_line
			(start -0.7874 -0.4064)
			(end -0.7874 0.4064)
			(stroke
				(width 0.1524)
				(type default)
			)
			(layer "B.SilkS")
		)
		(fp_line
			(start 0.7874 -0.4064)
			(end -0.7874 -0.4064)
			(stroke
				(width 0.1524)
				(type default)
			)
			(layer "B.SilkS")
		)
		(fp_line
			(start -0.67945 0.3048)
			(end -0.120396 0.3048)
			(stroke
				(width 0.1)
				(type default)
			)
			(layer "B.Fab")
		)
		(fp_line
			(start -0.120396 0.3048)
			(end -0.120396 0.2794)
			(stroke
				(width 0.1)
				(type default)
			)
			(layer "B.Fab")
		)
		(fp_line
			(start 0.12065 0.3048)
			(end 0.67945 0.3048)
			(stroke
				(width 0.1)
				(type default)
			)
			(layer "B.Fab")
		)
		(fp_line
			(start 0.67945 0.3048)
			(end 0.67945 -0.305054)
			(stroke
				(width 0.1)
				(type default)
			)
			(layer "B.Fab")
		)
		(fp_line
			(start -0.120396 0.2794)
			(end 0.12065 0.2794)
			(stroke
				(width 0.1)
				(type default)
			)
			(layer "B.Fab")
		)
		(fp_line
			(start 0.12065 0.2794)
			(end 0.12065 0.3048)
			(stroke
				(width 0.1)
				(type default)
			)
			(layer "B.Fab")
		)
		(fp_line
			(start -0.12065 -0.2794)
			(end -0.12065 -0.3048)
			(stroke
				(width 0.1)
				(type default)
			)
			(layer "B.Fab")
		)
		(fp_line
			(start 0.12065 -0.2794)
			(end -0.12065 -0.2794)
			(stroke
				(width 0.1)
				(type default)
			)
			(layer "B.Fab")
		)
		(fp_line
			(start -0.67945 -0.3048)
			(end -0.67945 0.3048)
			(stroke
				(width 0.1)
				(type default)
			)
			(layer "B.Fab")
		)
		(fp_line
			(start -0.12065 -0.3048)
			(end -0.67945 -0.3048)
			(stroke
				(width 0.1)
				(type default)
			)
			(layer "B.Fab")
		)
		(fp_line
			(start 0.12065 -0.305054)
			(end 0.12065 -0.2794)
			(stroke
				(width 0.1)
				(type default)
			)
			(layer "B.Fab")
		)
		(fp_line
			(start 0.67945 -0.305054)
			(end 0.12065 -0.305054)
			(stroke
				(width 0.1)
				(type default)
			)
			(layer "B.Fab")
		)
		(pad "1" smd circle
			(at 0.40005 0 90)
			(size 0 0)
			(layers "B.Cu" "B.Mask" "B.Paste")
			(net "PD_CK440_SBI_DATA_IN")
		)
		(pad "2" smd circle
			(at -0.40005 0 90)
			(size 0 0)
			(layers "B.Cu" "B.Mask" "B.Paste")
			(net "GND")
		)
	)
	(footprint ""
		(layer "B.Cu")
		(at 102.845616 -360.296968 180)
		(property "Reference" "R2522"
			(at 0 0 0)
			(layer "B.SilkS")
			(hide yes)
			(effects
				(font
					(size 1.27 1.27)
				)
				(justify mirror)
			)
		)
		(property "Value" ""
			(at 0 0 0)
			(layer "B.Fab")
			(effects
				(font
					(size 1.27 1.27)
				)
				(justify mirror)
			)
		)
		(duplicate_pad_numbers_are_jumpers no)
		(fp_line
			(start 0.7874 0.4064)
			(end 0.7874 -0.4064)
			(stroke
				(width 0.1524)
				(type default)
			)
			(layer "B.SilkS")
		)
		(fp_line
			(start 0.7874 -0.4064)
			(end -0.7874 -0.4064)
			(stroke
				(width 0.1524)
				(type default)
			)
			(layer "B.SilkS")
		)
		(fp_line
			(start -0.7874 0.4064)
			(end 0.7874 0.4064)
			(stroke
				(width 0.1524)
				(type default)
			)
			(layer "B.SilkS")
		)
		(fp_line
			(start -0.7874 -0.4064)
			(end -0.7874 0.4064)
			(stroke
				(width 0.1524)
				(type default)
			)
			(layer "B.SilkS")
		)
		(fp_line
			(start 0.67945 0.3048)
			(end 0.67945 -0.305054)
			(stroke
				(width 0.1)
				(type default)
			)
			(layer "B.Fab")
		)
		(fp_line
			(start 0.67945 -0.305054)
			(end 0.12065 -0.305054)
			(stroke
				(width 0.1)
				(type default)
			)
			(layer "B.Fab")
		)
		(fp_line
			(start 0.12065 0.3048)
			(end 0.67945 0.3048)
			(stroke
				(width 0.1)
				(type default)
			)
			(layer "B.Fab")
		)
		(fp_line
			(start 0.12065 0.2794)
			(end 0.12065 0.3048)
			(stroke
				(width 0.1)
				(type default)
			)
			(layer "B.Fab")
		)
		(fp_line
			(start 0.12065 -0.2794)
			(end -0.12065 -0.2794)
			(stroke
				(width 0.1)
				(type default)
			)
			(layer "B.Fab")
		)
		(fp_line
			(start 0.12065 -0.305054)
			(end 0.12065 -0.2794)
			(stroke
				(width 0.1)
				(type default)
			)
			(layer "B.Fab")
		)
		(fp_line
			(start -0.120396 0.3048)
			(end -0.120396 0.2794)
			(stroke
				(width 0.1)
				(type default)
			)
			(layer "B.Fab")
		)
		(fp_line
			(start -0.120396 0.2794)
			(end 0.12065 0.2794)
			(stroke
				(width 0.1)
				(type default)
			)
			(layer "B.Fab")
		)
		(fp_line
			(start -0.12065 -0.2794)
			(end -0.12065 -0.3048)
			(stroke
				(width 0.1)
				(type default)
			)
			(layer "B.Fab")
		)
		(fp_line
			(start -0.12065 -0.3048)
			(end -0.67945 -0.3048)
			(stroke
				(width 0.1)
				(type default)
			)
			(layer "B.Fab")
		)
		(fp_line
			(start -0.67945 0.3048)
			(end -0.120396 0.3048)
			(stroke
				(width 0.1)
				(type default)
			)
			(layer "B.Fab")
		)
		(fp_line
			(start -0.67945 -0.3048)
			(end -0.67945 0.3048)
			(stroke
				(width 0.1)
				(type default)
			)
			(layer "B.Fab")
		)
		(pad "1" smd circle
			(at 0.40005 0)
			(size 0 0)
			(layers "B.Cu" "B.Mask" "B.Paste")
			(net "P3V3_AUX")
		)
		(pad "2" smd circle
			(at -0.40005 0)
			(size 0 0)
			(layers "B.Cu" "B.Mask" "B.Paste")
			(net "IRQ_PVCCIN_CPU1_VRHOT_R_N")
		)
	)
)
